(kicad_pcb
	(version 20260206)
	(generator "pcbnew")
	(generator_version "10.0")
	(general
		(thickness 1.6)
		(legacy_teardrops no)
	)
	(paper "A4")
	(title_block
		(title "15969-1a.1015WZS0858.brd")
		(comment 1 "Tioga Pass / footprints 202-209 of 295")
	)
	(layers
		(0 "F.Cu" signal "TOP")
		(4 "In1.Cu" signal "L2GND")
		(6 "In2.Cu" signal "L3")
		(8 "In3.Cu" signal "L4")
		(10 "In4.Cu" signal "L5GND")
		(2 "B.Cu" signal "BOTTOM")
		(9 "F.Adhes" user "F.Adhesive")
		(11 "B.Adhes" user "B.Adhesive")
		(13 "F.Paste" user "Package Geometry/Pastemask Top")
		(15 "B.Paste" user "Package Geometry/Pastemask Bottom")
		(5 "F.SilkS" user "Ref Des/Silkscreen Top")
		(7 "B.SilkS" user "Ref Des/Silkscreen Bottom")
		(1 "F.Mask" user "Board Geometry/Soldermask Top")
		(3 "B.Mask" user "Board Geometry/Soldermask Bottom")
		(17 "Dwgs.User" user "User.Drawings")
		(19 "Cmts.User" user "User.Comments")
		(21 "Eco1.User" user "User.Eco1")
		(23 "Eco2.User" user "User.Eco2")
		(25 "Edge.Cuts" user "Board Geometry/Outline")
		(27 "Margin" user)
		(31 "F.CrtYd" user "Package Geometry/Place Bound Top")
		(29 "B.CrtYd" user "Package Geometry/Place Bound Bottom")
		(35 "F.Fab" user "Ref Des/Assembly Top")
		(33 "B.Fab" user "Ref Des/Assembly Bottom")
	)
	(footprint ""
		(layer "B.Cu")
		(at 130.2766 -22.4028)
		(property "Reference" "R174"
			(at 0 0 0)
			(layer "B.SilkS")
			(hide yes)
			(effects
				(font
					(size 1.27 1.27)
				)
				(justify mirror)
			)
		)
		(property "Value" "0R2F-1-GP"
			(at -0.064008 -3.993896 0)
			(unlocked yes)
			(layer "B.Fab")
			(hide yes)
			(effects
				(font
					(size 1.016 1.016)
					(thickness 0.1524)
				)
				(justify mirror)
			)
		)
		(property "Device Type" "R402H16"
			(at -0.064008 -5.517896 0)
			(unlocked yes)
			(layer "B.Fab")
			(hide yes)
			(effects
				(font
					(size 1.016 1.016)
					(thickness 0.1524)
				)
				(justify mirror)
			)
		)
		(duplicate_pad_numbers_are_jumpers no)
		(fp_line
			(start -0.508 -0.9398)
			(end 0.508 -0.9398)
			(stroke
				(width 0.1524)
				(type default)
			)
			(layer "B.SilkS")
		)
		(fp_line
			(start 0.508 -0.9398)
			(end 0.508 0.9398)
			(stroke
				(width 0.1524)
				(type default)
			)
			(layer "B.SilkS")
		)
		(fp_rect
			(start 0.508 0.9398)
			(end -0.508 -0.9398)
			(stroke
				(width 0)
				(type default)
			)
			(fill no)
			(layer "B.CrtYd")
		)
		(fp_rect
			(start 0.508 0.9398)
			(end -0.508 -0.9398)
			(stroke
				(width 0)
				(type default)
			)
			(fill no)
			(layer "B.Fab")
		)
		(pad "1" smd custom
			(at 0 -0.4445 180)
			(size 0.1397 0.1397)
			(layers "B.Cu" "B.Mask" "B.Paste")
			(net "SMCLK_USB_HUB")
			(options
				(clearance outline)
				(anchor circle)
			)
			(primitives
				(gr_poly
					(pts
						(arc
							(start -0.1778 0.2794)
							(mid -0.249642 0.249642)
							(end -0.2794 0.1778)
						)
						(arc
							(start -0.2794 -0.1778)
							(mid -0.249642 -0.249642)
							(end -0.1778 -0.2794)
						)
						(arc
							(start 0.1778 -0.2794)
							(mid 0.249642 -0.249642)
							(end 0.2794 -0.1778)
						)
						(arc
							(start 0.2794 0.1778)
							(mid 0.249642 0.249642)
							(end 0.1778 0.2794)
						)
					)
					(width 0)
					(fill yes)
				)
			)
		)
		(pad "2" smd custom
			(at 0 0.4445 180)
			(size 0.1397 0.1397)
			(layers "B.Cu" "B.Mask" "B.Paste")
			(net "SMCLK_BMC_DEVICE")
			(options
				(clearance outline)
				(anchor circle)
			)
			(primitives
				(gr_poly
					(pts
						(arc
							(start -0.1778 0.2794)
							(mid -0.249642 0.249642)
							(end -0.2794 0.1778)
						)
						(arc
							(start -0.2794 -0.1778)
							(mid -0.249642 -0.249642)
							(end -0.1778 -0.2794)
						)
						(arc
							(start 0.1778 -0.2794)
							(mid 0.249642 -0.249642)
							(end 0.2794 -0.1778)
						)
						(arc
							(start 0.2794 0.1778)
							(mid 0.249642 0.249642)
							(end 0.1778 0.2794)
						)
					)
					(width 0)
					(fill yes)
				)
			)
		)
	)
	(footprint ""
		(layer "B.Cu")
		(at 118.1862 -18.796 -90)
		(property "Reference" "RU153"
			(at 0 0 90)
			(layer "B.SilkS")
			(hide yes)
			(effects
				(font
					(size 1.27 1.27)
				)
				(justify mirror)
			)
		)
		(property "Value" "4K7R2F-GP"
			(at -0.064008 -3.993896 270)
			(unlocked yes)
			(layer "B.Fab")
			(hide yes)
			(effects
				(font
					(size 1.016 1.016)
					(thickness 0.1524)
				)
				(justify mirror)
			)
		)
		(property "Device Type" "R402H16"
			(at -0.064008 -5.517896 270)
			(unlocked yes)
			(layer "B.Fab")
			(hide yes)
			(effects
				(font
					(size 1.016 1.016)
					(thickness 0.1524)
				)
				(justify mirror)
			)
		)
		(duplicate_pad_numbers_are_jumpers no)
		(fp_line
			(start -0.508 -0.9398)
			(end 0.508 -0.9398)
			(stroke
				(width 0.1524)
				(type default)
			)
			(layer "B.SilkS")
		)
		(fp_line
			(start 0.508 -0.9398)
			(end 0.508 0.9398)
			(stroke
				(width 0.1524)
				(type default)
			)
			(layer "B.SilkS")
		)
		(fp_rect
			(start 0.508 0.9398)
			(end -0.508 -0.9398)
			(stroke
				(width 0)
				(type default)
			)
			(fill no)
			(layer "B.CrtYd")
		)
		(fp_rect
			(start 0.508 0.9398)
			(end -0.508 -0.9398)
			(stroke
				(width 0)
				(type default)
			)
			(fill no)
			(layer "B.Fab")
		)
		(pad "1" smd custom
			(at 0 -0.4445 90)
			(size 0.1397 0.1397)
			(layers "B.Cu" "B.Mask" "B.Paste")
			(net "SMDAT_USB_HUB_R")
			(options
				(clearance outline)
				(anchor circle)
			)
			(primitives
				(gr_poly
					(pts
						(arc
							(start -0.1778 0.2794)
							(mid -0.249642 0.249642)
							(end -0.2794 0.1778)
						)
						(arc
							(start -0.2794 -0.1778)
							(mid -0.249642 -0.249642)
							(end -0.1778 -0.2794)
						)
						(arc
							(start 0.1778 -0.2794)
							(mid 0.249642 -0.249642)
							(end 0.2794 -0.1778)
						)
						(arc
							(start 0.2794 0.1778)
							(mid 0.249642 0.249642)
							(end 0.1778 0.2794)
						)
					)
					(width 0)
					(fill yes)
				)
			)
		)
		(pad "2" smd custom
			(at 0 0.4445 90)
			(size 0.1397 0.1397)
			(layers "B.Cu" "B.Mask" "B.Paste")
			(net "P3V3_USB_HUB")
			(options
				(clearance outline)
				(anchor circle)
			)
			(primitives
				(gr_poly
					(pts
						(arc
							(start -0.1778 0.2794)
							(mid -0.249642 0.249642)
							(end -0.2794 0.1778)
						)
						(arc
							(start -0.2794 -0.1778)
							(mid -0.249642 -0.249642)
							(end -0.1778 -0.2794)
						)
						(arc
							(start 0.1778 -0.2794)
							(mid 0.249642 -0.249642)
							(end 0.2794 -0.1778)
						)
						(arc
							(start 0.2794 0.1778)
							(mid 0.249642 0.249642)
							(end 0.1778 0.2794)
						)
					)
					(width 0)
					(fill yes)
				)
			)
		)
	)
	(footprint ""
		(layer "B.Cu")
		(at 107.1626 4.1656 -90)
		(property "Reference" "R48"
			(at 0 0 90)
			(layer "B.SilkS")
			(hide yes)
			(effects
				(font
					(size 1.27 1.27)
				)
				(justify mirror)
			)
		)
		(property "Value" "0R2F-1-GP"
			(at -0.064008 -3.993896 270)
			(unlocked yes)
			(layer "B.Fab")
			(hide yes)
			(effects
				(font
					(size 1.016 1.016)
					(thickness 0.1524)
				)
				(justify mirror)
			)
		)
		(property "Device Type" "R402H16"
			(at -0.064008 -5.517896 270)
			(unlocked yes)
			(layer "B.Fab")
			(hide yes)
			(effects
				(font
					(size 1.016 1.016)
					(thickness 0.1524)
				)
				(justify mirror)
			)
		)
		(duplicate_pad_numbers_are_jumpers no)
		(fp_line
			(start -0.508 -0.9398)
			(end 0.508 -0.9398)
			(stroke
				(width 0.1524)
				(type default)
			)
			(layer "B.SilkS")
		)
		(fp_line
			(start 0.508 -0.9398)
			(end 0.508 0.9398)
			(stroke
				(width 0.1524)
				(type default)
			)
			(layer "B.SilkS")
		)
		(fp_rect
			(start 0.508 0.9398)
			(end -0.508 -0.9398)
			(stroke
				(width 0)
				(type default)
			)
			(fill no)
			(layer "B.CrtYd")
		)
		(fp_rect
			(start 0.508 0.9398)
			(end -0.508 -0.9398)
			(stroke
				(width 0)
				(type default)
			)
			(fill no)
			(layer "B.Fab")
		)
		(pad "1" smd custom
			(at 0 -0.4445 90)
			(size 0.1397 0.1397)
			(layers "B.Cu" "B.Mask" "B.Paste")
			(net "SMCLK_BMC_R")
			(options
				(clearance outline)
				(anchor circle)
			)
			(primitives
				(gr_poly
					(pts
						(arc
							(start -0.1778 0.2794)
							(mid -0.249642 0.249642)
							(end -0.2794 0.1778)
						)
						(arc
							(start -0.2794 -0.1778)
							(mid -0.249642 -0.249642)
							(end -0.1778 -0.2794)
						)
						(arc
							(start 0.1778 -0.2794)
							(mid 0.249642 -0.249642)
							(end 0.2794 -0.1778)
						)
						(arc
							(start 0.2794 0.1778)
							(mid 0.249642 0.249642)
							(end 0.1778 0.2794)
						)
					)
					(width 0)
					(fill yes)
				)
			)
		)
		(pad "2" smd custom
			(at 0 0.4445 90)
			(size 0.1397 0.1397)
			(layers "B.Cu" "B.Mask" "B.Paste")
			(net "SMB_SLOTX24_STBY_LVC3_SCL_R2")
			(options
				(clearance outline)
				(anchor circle)
			)
			(primitives
				(gr_poly
					(pts
						(arc
							(start -0.1778 0.2794)
							(mid -0.249642 0.249642)
							(end -0.2794 0.1778)
						)
						(arc
							(start -0.2794 -0.1778)
							(mid -0.249642 -0.249642)
							(end -0.1778 -0.2794)
						)
						(arc
							(start 0.1778 -0.2794)
							(mid 0.249642 -0.249642)
							(end 0.2794 -0.1778)
						)
						(arc
							(start 0.2794 0.1778)
							(mid 0.249642 0.249642)
							(end 0.1778 0.2794)
						)
					)
					(width 0)
					(fill yes)
				)
			)
		)
	)
	(footprint ""
		(layer "B.Cu")
		(at 132.2578 -7.7978 -90)
		(property "Reference" "R67"
			(at 0 0 90)
			(layer "B.SilkS")
			(hide yes)
			(effects
				(font
					(size 1.27 1.27)
				)
				(justify mirror)
			)
		)
		(property "Value" "4K7R2F-GP"
			(at -0.064008 -3.993896 270)
			(unlocked yes)
			(layer "B.Fab")
			(hide yes)
			(effects
				(font
					(size 1.016 1.016)
					(thickness 0.1524)
				)
				(justify mirror)
			)
		)
		(property "Device Type" "R402H16"
			(at -0.064008 -5.517896 270)
			(unlocked yes)
			(layer "B.Fab")
			(hide yes)
			(effects
				(font
					(size 1.016 1.016)
					(thickness 0.1524)
				)
				(justify mirror)
			)
		)
		(duplicate_pad_numbers_are_jumpers no)
		(fp_line
			(start -0.508 -0.9398)
			(end 0.508 -0.9398)
			(stroke
				(width 0.1524)
				(type default)
			)
			(layer "B.SilkS")
		)
		(fp_line
			(start 0.508 -0.9398)
			(end 0.508 0.9398)
			(stroke
				(width 0.1524)
				(type default)
			)
			(layer "B.SilkS")
		)
		(fp_rect
			(start 0.508 0.9398)
			(end -0.508 -0.9398)
			(stroke
				(width 0)
				(type default)
			)
			(fill no)
			(layer "B.CrtYd")
		)
		(fp_rect
			(start 0.508 0.9398)
			(end -0.508 -0.9398)
			(stroke
				(width 0)
				(type default)
			)
			(fill no)
			(layer "B.Fab")
		)
		(pad "1" smd custom
			(at 0 -0.4445 90)
			(size 0.1397 0.1397)
			(layers "B.Cu" "B.Mask" "B.Paste")
			(net "P3V3_STBY")
			(options
				(clearance outline)
				(anchor circle)
			)
			(primitives
				(gr_poly
					(pts
						(arc
							(start -0.1778 0.2794)
							(mid -0.249642 0.249642)
							(end -0.2794 0.1778)
						)
						(arc
							(start -0.2794 -0.1778)
							(mid -0.249642 -0.249642)
							(end -0.1778 -0.2794)
						)
						(arc
							(start 0.1778 -0.2794)
							(mid 0.249642 -0.249642)
							(end 0.2794 -0.1778)
						)
						(arc
							(start 0.2794 0.1778)
							(mid 0.249642 0.249642)
							(end 0.1778 0.2794)
						)
					)
					(width 0)
					(fill yes)
				)
			)
		)
		(pad "2" smd custom
			(at 0 0.4445 90)
			(size 0.1397 0.1397)
			(layers "B.Cu" "B.Mask" "B.Paste")
			(net "GPIO_P_EXP_INT_N")
			(options
				(clearance outline)
				(anchor circle)
			)
			(primitives
				(gr_poly
					(pts
						(arc
							(start -0.1778 0.2794)
							(mid -0.249642 0.249642)
							(end -0.2794 0.1778)
						)
						(arc
							(start -0.2794 -0.1778)
							(mid -0.249642 -0.249642)
							(end -0.1778 -0.2794)
						)
						(arc
							(start 0.1778 -0.2794)
							(mid 0.249642 -0.249642)
							(end 0.2794 -0.1778)
						)
						(arc
							(start 0.2794 0.1778)
							(mid 0.249642 0.249642)
							(end 0.1778 0.2794)
						)
					)
					(width 0)
					(fill yes)
				)
			)
		)
	)
	(footprint ""
		(layer "B.Cu")
		(at 120.8278 -22.86 180)
		(property "Reference" "R111"
			(at 0 0 0)
			(layer "B.SilkS")
			(hide yes)
			(effects
				(font
					(size 1.27 1.27)
				)
				(justify mirror)
			)
		)
		(property "Value" "0R2F-1-GP"
			(at -0.064008 -3.993896 180)
			(unlocked yes)
			(layer "B.Fab")
			(hide yes)
			(effects
				(font
					(size 1.016 1.016)
					(thickness 0.1524)
				)
				(justify mirror)
			)
		)
		(property "Device Type" "R402H16"
			(at -0.064008 -5.517896 180)
			(unlocked yes)
			(layer "B.Fab")
			(hide yes)
			(effects
				(font
					(size 1.016 1.016)
					(thickness 0.1524)
				)
				(justify mirror)
			)
		)
		(duplicate_pad_numbers_are_jumpers no)
		(fp_line
			(start 0.508 -0.9398)
			(end 0.508 0.9398)
			(stroke
				(width 0.1524)
				(type default)
			)
			(layer "B.SilkS")
		)
		(fp_line
			(start -0.508 -0.9398)
			(end 0.508 -0.9398)
			(stroke
				(width 0.1524)
				(type default)
			)
			(layer "B.SilkS")
		)
		(fp_rect
			(start 0.508 0.9398)
			(end -0.508 -0.9398)
			(stroke
				(width 0)
				(type default)
			)
			(fill no)
			(layer "B.CrtYd")
		)
		(fp_rect
			(start 0.508 0.9398)
			(end -0.508 -0.9398)
			(stroke
				(width 0)
				(type default)
			)
			(fill no)
			(layer "B.Fab")
		)
		(pad "1" smd custom
			(at 0 -0.4445)
			(size 0.1397 0.1397)
			(layers "B.Cu" "B.Mask" "B.Paste")
			(net "SMCLK_USB_HUB_R")
			(options
				(clearance outline)
				(anchor circle)
			)
			(primitives
				(gr_poly
					(pts
						(arc
							(start -0.1778 0.2794)
							(mid -0.249642 0.249642)
							(end -0.2794 0.1778)
						)
						(arc
							(start -0.2794 -0.1778)
							(mid -0.249642 -0.249642)
							(end -0.1778 -0.2794)
						)
						(arc
							(start 0.1778 -0.2794)
							(mid 0.249642 -0.249642)
							(end 0.2794 -0.1778)
						)
						(arc
							(start 0.2794 0.1778)
							(mid 0.249642 0.249642)
							(end 0.1778 0.2794)
						)
					)
					(width 0)
					(fill yes)
				)
			)
		)
		(pad "2" smd custom
			(at 0 0.4445)
			(size 0.1397 0.1397)
			(layers "B.Cu" "B.Mask" "B.Paste")
			(net "SMCLK_USB_HUB")
			(options
				(clearance outline)
				(anchor circle)
			)
			(primitives
				(gr_poly
					(pts
						(arc
							(start -0.1778 0.2794)
							(mid -0.249642 0.249642)
							(end -0.2794 0.1778)
						)
						(arc
							(start -0.2794 -0.1778)
							(mid -0.249642 -0.249642)
							(end -0.1778 -0.2794)
						)
						(arc
							(start 0.1778 -0.2794)
							(mid 0.249642 -0.249642)
							(end 0.2794 -0.1778)
						)
						(arc
							(start 0.2794 0.1778)
							(mid 0.249642 0.249642)
							(end 0.1778 0.2794)
						)
					)
					(width 0)
					(fill yes)
				)
			)
		)
	)
	(footprint ""
		(layer "B.Cu")
		(at 28.4607 2.1971)
		(property "Reference" "PC7"
			(at 0 0 0)
			(layer "B.SilkS")
			(hide yes)
			(effects
				(font
					(size 1.27 1.27)
				)
				(justify mirror)
			)
		)
		(property "Value" "SC22U6D3V5MX-5-GP"
			(at 0.0762 -6.1214 0)
			(unlocked yes)
			(layer "B.Fab")
			(hide yes)
			(effects
				(font
					(size 1.016 1.016)
					(thickness 0.1524)
				)
				(justify mirror)
			)
		)
		(property "Device Type" "C805H56"
			(at 0.0762 -8.1534 0)
			(unlocked yes)
			(layer "B.Fab")
			(hide yes)
			(effects
				(font
					(size 1.016 1.016)
					(thickness 0.1524)
				)
				(justify mirror)
			)
		)
		(duplicate_pad_numbers_are_jumpers no)
		(fp_line
			(start -0.635 0)
			(end 0.635 0)
			(stroke
				(width 0.508)
				(type default)
			)
			(layer "B.SilkS")
		)
		(fp_rect
			(start 0.9652 1.778)
			(end -0.9652 -1.778)
			(stroke
				(width 0)
				(type default)
			)
			(fill no)
			(layer "B.CrtYd")
		)
		(fp_poly
			(pts
				(xy 0.9652 -1.778) (xy -0.9652 -1.778) (xy -0.9652 1.778) (xy 0.9652 1.778)
			)
			(stroke
				(width 0)
				(type default)
			)
			(fill no)
			(layer "B.Fab")
		)
		(pad "1" smd rect
			(at 0 -0.9652 180)
			(size 1.397 1.143)
			(layers "B.Cu" "B.Mask" "B.Paste")
			(net "P3V3_VR")
		)
		(pad "2" smd rect
			(at 0 0.9652 180)
			(size 1.397 1.143)
			(layers "B.Cu" "B.Mask" "B.Paste")
			(net "GND")
		)
	)
	(footprint ""
		(layer "B.Cu")
		(at 32.8422 1.1557 -90)
		(property "Reference" "C58"
			(at 0 0 90)
			(layer "B.SilkS")
			(hide yes)
			(effects
				(font
					(size 1.27 1.27)
				)
				(justify mirror)
			)
		)
		(property "Value" "SCD1U16V2KX-3GP"
			(at -1.1811 -2.7051 270)
			(unlocked yes)
			(layer "B.Fab")
			(hide yes)
			(effects
				(font
					(size 1.016 1.016)
					(thickness 0.1524)
				)
				(justify mirror)
			)
		)
		(property "Device Type" "C402H22"
			(at -1.1811 -4.2291 270)
			(unlocked yes)
			(layer "B.Fab")
			(hide yes)
			(effects
				(font
					(size 1.016 1.016)
					(thickness 0.1524)
				)
				(justify mirror)
			)
		)
		(duplicate_pad_numbers_are_jumpers no)
		(fp_rect
			(start 0.4318 0.9525)
			(end -0.4318 -0.9525)
			(stroke
				(width 0)
				(type default)
			)
			(fill no)
			(layer "B.CrtYd")
		)
		(fp_rect
			(start 0.4318 0.9525)
			(end -0.4318 -0.9525)
			(stroke
				(width 0)
				(type default)
			)
			(fill no)
			(layer "B.Fab")
		)
		(pad "1" smd custom
			(at 0 -0.4445 90)
			(size 0.1524 0.1524)
			(layers "B.Cu" "B.Mask" "B.Paste")
			(net "P3V3_STBY")
			(options
				(clearance outline)
				(anchor circle)
			)
			(primitives
				(gr_poly
					(pts
						(arc
							(start 0.3048 0.2032)
							(mid 0.275042 0.275042)
							(end 0.2032 0.3048)
						)
						(arc
							(start -0.2032 0.3048)
							(mid -0.275042 0.275042)
							(end -0.3048 0.2032)
						)
						(arc
							(start -0.3048 -0.2032)
							(mid -0.275042 -0.275042)
							(end -0.2032 -0.3048)
						)
						(arc
							(start 0.2032 -0.3048)
							(mid 0.275042 -0.275042)
							(end 0.3048 -0.2032)
						)
					)
					(width 0)
					(fill yes)
				)
			)
		)
		(pad "2" smd custom
			(at 0 0.4445 90)
			(size 0.1524 0.1524)
			(layers "B.Cu" "B.Mask" "B.Paste")
			(net "GND")
			(options
				(clearance outline)
				(anchor circle)
			)
			(primitives
				(gr_poly
					(pts
						(arc
							(start 0.3048 0.2032)
							(mid 0.275042 0.275042)
							(end 0.2032 0.3048)
						)
						(arc
							(start -0.2032 0.3048)
							(mid -0.275042 0.275042)
							(end -0.3048 0.2032)
						)
						(arc
							(start -0.3048 -0.2032)
							(mid -0.275042 -0.275042)
							(end -0.2032 -0.3048)
						)
						(arc
							(start 0.2032 -0.3048)
							(mid 0.275042 -0.275042)
							(end 0.3048 -0.2032)
						)
					)
					(width 0)
					(fill yes)
				)
			)
		)
	)
	(footprint ""
		(layer "B.Cu")
		(at 18.7706 -19.3802 90)
		(property "Reference" "C53"
			(at 0 0 90)
			(layer "B.SilkS")
			(hide yes)
			(effects
				(font
					(size 1.27 1.27)
				)
				(justify mirror)
			)
		)
		(property "Value" "SCD1U25V2KX-2-GP"
			(at -1.1811 -2.7051 90)
			(unlocked yes)
			(layer "B.Fab")
			(hide yes)
			(effects
				(font
					(size 1.016 1.016)
					(thickness 0.1524)
				)
				(justify mirror)
			)
		)
		(property "Device Type" "C402H22"
			(at -1.1811 -4.2291 90)
			(unlocked yes)
			(layer "B.Fab")
			(hide yes)
			(effects
				(font
					(size 1.016 1.016)
					(thickness 0.1524)
				)
				(justify mirror)
			)
		)
		(duplicate_pad_numbers_are_jumpers no)
		(fp_rect
			(start 0.4318 0.9525)
			(end -0.4318 -0.9525)
			(stroke
				(width 0)
				(type default)
			)
			(fill no)
			(layer "B.CrtYd")
		)
		(fp_rect
			(start 0.4318 0.9525)
			(end -0.4318 -0.9525)
			(stroke
				(width 0)
				(type default)
			)
			(fill no)
			(layer "B.Fab")
		)
		(pad "1" smd custom
			(at 0 -0.4445 270)
			(size 0.1524 0.1524)
			(layers "B.Cu" "B.Mask" "B.Paste")
			(net "P12V")
			(options
				(clearance outline)
				(anchor circle)
			)
			(primitives
				(gr_poly
					(pts
						(arc
							(start 0.3048 0.2032)
							(mid 0.275042 0.275042)
							(end 0.2032 0.3048)
						)
						(arc
							(start -0.2032 0.3048)
							(mid -0.275042 0.275042)
							(end -0.3048 0.2032)
						)
						(arc
							(start -0.3048 -0.2032)
							(mid -0.275042 -0.275042)
							(end -0.2032 -0.3048)
						)
						(arc
							(start 0.2032 -0.3048)
							(mid 0.275042 -0.275042)
							(end 0.3048 -0.2032)
						)
					)
					(width 0)
					(fill yes)
				)
			)
		)
		(pad "2" smd custom
			(at 0 0.4445 270)
			(size 0.1524 0.1524)
			(layers "B.Cu" "B.Mask" "B.Paste")
			(net "GND")
			(options
				(clearance outline)
				(anchor circle)
			)
			(primitives
				(gr_poly
					(pts
						(arc
							(start 0.3048 0.2032)
							(mid 0.275042 0.275042)
							(end 0.2032 0.3048)
						)
						(arc
							(start -0.2032 0.3048)
							(mid -0.275042 0.275042)
							(end -0.3048 0.2032)
						)
						(arc
							(start -0.3048 -0.2032)
							(mid -0.275042 -0.275042)
							(end -0.2032 -0.3048)
						)
						(arc
							(start 0.2032 -0.3048)
							(mid 0.275042 -0.275042)
							(end 0.3048 -0.2032)
						)
					)
					(width 0)
					(fill yes)
				)
			)
		)
	)
)
